(kicad_pcb
	(version 20260206)
	(generator "pcbnew")
	(generator_version "10.0")
	(general
		(thickness 1.6)
		(legacy_teardrops no)
	)
	(paper "A4")
	(title_block
		(title "04192023_DAF0TMB3IC0_F0TG_MB_C_brd_V02_OCP.brd")
		(comment 1 "Grand Teton / footprints 3034-3041 of 8354")
	)
	(layers
		(0 "F.Cu" signal "TOP")
		(4 "In1.Cu" signal "GND")
		(6 "In2.Cu" signal "IN1")
		(8 "In3.Cu" signal "GND1")
		(10 "In4.Cu" signal "IN2")
		(12 "In5.Cu" signal "GND2")
		(14 "In6.Cu" signal "IN3")
		(16 "In7.Cu" signal "GND3")
		(18 "In8.Cu" signal "VCC")
		(20 "In9.Cu" signal "VCC1")
		(22 "In10.Cu" signal "GND4")
		(24 "In11.Cu" signal "IN4")
		(26 "In12.Cu" signal "GND5")
		(28 "In13.Cu" signal "IN5")
		(30 "In14.Cu" signal "GND6")
		(32 "In15.Cu" signal "IN6")
		(34 "In16.Cu" signal "GND7")
		(2 "B.Cu" signal "BOTTOM")
		(9 "F.Adhes" user "F.Adhesive")
		(11 "B.Adhes" user "B.Adhesive")
		(13 "F.Paste" user "Package Geometry/Pastemask Top")
		(15 "B.Paste" user "Package Geometry/Pastemask Bottom")
		(5 "F.SilkS" user "Ref Des/Silkscreen Top")
		(7 "B.SilkS" user "Ref Des/Silkscreen Bottom")
		(1 "F.Mask" user "Board Geometry/Soldermask Top")
		(3 "B.Mask" user "Board Geometry/Soldermask Bottom")
		(17 "Dwgs.User" user "User.Drawings")
		(19 "Cmts.User" user "User.Comments")
		(21 "Eco1.User" user "User.Eco1")
		(23 "Eco2.User" user "User.Eco2")
		(25 "Edge.Cuts" user "Board Geometry/Outline")
		(27 "Margin" user)
		(31 "F.CrtYd" user "Package Geometry/Place Bound Top")
		(29 "B.CrtYd" user "Package Geometry/Place Bound Bottom")
		(35 "F.Fab" user "Ref Des/Assembly Top")
		(33 "B.Fab" user "Ref Des/Assembly Bottom")
	)
	(footprint ""
		(layer "F.Cu")
		(at 287.339024 -398.913858 90)
		(property "Reference" "C1787"
			(at 0 0 90)
			(layer "F.SilkS")
			(hide yes)
			(effects
				(font
					(size 1.27 1.27)
				)
			)
		)
		(property "Value" ""
			(at 0 0 90)
			(layer "F.Fab")
			(effects
				(font
					(size 1.27 1.27)
				)
			)
		)
		(duplicate_pad_numbers_are_jumpers no)
		(fp_line
			(start 0.7874 -0.4064)
			(end 0.7874 0.4064)
			(stroke
				(width 0.1524)
				(type default)
			)
			(layer "F.SilkS")
		)
		(fp_line
			(start -0.7874 -0.4064)
			(end 0.7874 -0.4064)
			(stroke
				(width 0.1524)
				(type default)
			)
			(layer "F.SilkS")
		)
		(fp_line
			(start 0.7874 0.4064)
			(end -0.7874 0.4064)
			(stroke
				(width 0.1524)
				(type default)
			)
			(layer "F.SilkS")
		)
		(fp_line
			(start -0.7874 0.4064)
			(end -0.7874 -0.4064)
			(stroke
				(width 0.1524)
				(type default)
			)
			(layer "F.SilkS")
		)
		(fp_line
			(start -0.12065 -0.305054)
			(end -0.12065 -0.2794)
			(stroke
				(width 0.1)
				(type default)
			)
			(layer "F.Fab")
		)
		(fp_line
			(start -0.67945 -0.305054)
			(end -0.12065 -0.305054)
			(stroke
				(width 0.1)
				(type default)
			)
			(layer "F.Fab")
		)
		(fp_line
			(start 0.67945 -0.3048)
			(end 0.67945 0.3048)
			(stroke
				(width 0.1)
				(type default)
			)
			(layer "F.Fab")
		)
		(fp_line
			(start 0.12065 -0.3048)
			(end 0.67945 -0.3048)
			(stroke
				(width 0.1)
				(type default)
			)
			(layer "F.Fab")
		)
		(fp_line
			(start 0.12065 -0.2794)
			(end 0.12065 -0.3048)
			(stroke
				(width 0.1)
				(type default)
			)
			(layer "F.Fab")
		)
		(fp_line
			(start -0.12065 -0.2794)
			(end 0.12065 -0.2794)
			(stroke
				(width 0.1)
				(type default)
			)
			(layer "F.Fab")
		)
		(fp_line
			(start 0.120396 0.2794)
			(end -0.12065 0.2794)
			(stroke
				(width 0.1)
				(type default)
			)
			(layer "F.Fab")
		)
		(fp_line
			(start -0.12065 0.2794)
			(end -0.12065 0.3048)
			(stroke
				(width 0.1)
				(type default)
			)
			(layer "F.Fab")
		)
		(fp_line
			(start 0.67945 0.3048)
			(end 0.120396 0.3048)
			(stroke
				(width 0.1)
				(type default)
			)
			(layer "F.Fab")
		)
		(fp_line
			(start 0.120396 0.3048)
			(end 0.120396 0.2794)
			(stroke
				(width 0.1)
				(type default)
			)
			(layer "F.Fab")
		)
		(fp_line
			(start -0.12065 0.3048)
			(end -0.67945 0.3048)
			(stroke
				(width 0.1)
				(type default)
			)
			(layer "F.Fab")
		)
		(fp_line
			(start -0.67945 0.3048)
			(end -0.67945 -0.305054)
			(stroke
				(width 0.1)
				(type default)
			)
			(layer "F.Fab")
		)
		(pad "1" smd circle
			(at -0.40005 0 90)
			(size 0 0)
			(layers "F.Cu" "F.Mask" "F.Paste")
			(net "P3V3_AUX")
		)
		(pad "2" smd circle
			(at 0.40005 0 90)
			(size 0 0)
			(layers "F.Cu" "F.Mask" "F.Paste")
			(net "GND")
		)
	)
	(footprint ""
		(layer "F.Cu")
		(at 26.947622 -405.840438)
		(property "Reference" "PC6620"
			(at 0 0 0)
			(layer "F.SilkS")
			(hide yes)
			(effects
				(font
					(size 1.27 1.27)
				)
			)
		)
		(property "Value" ""
			(at 0 0 0)
			(layer "F.Fab")
			(effects
				(font
					(size 1.27 1.27)
				)
			)
		)
		(duplicate_pad_numbers_are_jumpers no)
		(fp_line
			(start -0.7874 -0.4064)
			(end 0.7874 -0.4064)
			(stroke
				(width 0.1524)
				(type default)
			)
			(layer "F.SilkS")
		)
		(fp_line
			(start -0.7874 0.4064)
			(end -0.7874 -0.4064)
			(stroke
				(width 0.1524)
				(type default)
			)
			(layer "F.SilkS")
		)
		(fp_line
			(start 0.7874 -0.4064)
			(end 0.7874 0.4064)
			(stroke
				(width 0.1524)
				(type default)
			)
			(layer "F.SilkS")
		)
		(fp_line
			(start 0.7874 0.4064)
			(end -0.7874 0.4064)
			(stroke
				(width 0.1524)
				(type default)
			)
			(layer "F.SilkS")
		)
		(fp_line
			(start -0.67945 -0.305054)
			(end -0.12065 -0.305054)
			(stroke
				(width 0.1)
				(type default)
			)
			(layer "F.Fab")
		)
		(fp_line
			(start -0.67945 0.3048)
			(end -0.67945 -0.305054)
			(stroke
				(width 0.1)
				(type default)
			)
			(layer "F.Fab")
		)
		(fp_line
			(start -0.12065 -0.305054)
			(end -0.12065 -0.2794)
			(stroke
				(width 0.1)
				(type default)
			)
			(layer "F.Fab")
		)
		(fp_line
			(start -0.12065 -0.2794)
			(end 0.12065 -0.2794)
			(stroke
				(width 0.1)
				(type default)
			)
			(layer "F.Fab")
		)
		(fp_line
			(start -0.12065 0.2794)
			(end -0.12065 0.3048)
			(stroke
				(width 0.1)
				(type default)
			)
			(layer "F.Fab")
		)
		(fp_line
			(start -0.12065 0.3048)
			(end -0.67945 0.3048)
			(stroke
				(width 0.1)
				(type default)
			)
			(layer "F.Fab")
		)
		(fp_line
			(start 0.120396 0.2794)
			(end -0.12065 0.2794)
			(stroke
				(width 0.1)
				(type default)
			)
			(layer "F.Fab")
		)
		(fp_line
			(start 0.120396 0.3048)
			(end 0.120396 0.2794)
			(stroke
				(width 0.1)
				(type default)
			)
			(layer "F.Fab")
		)
		(fp_line
			(start 0.12065 -0.3048)
			(end 0.67945 -0.3048)
			(stroke
				(width 0.1)
				(type default)
			)
			(layer "F.Fab")
		)
		(fp_line
			(start 0.12065 -0.2794)
			(end 0.12065 -0.3048)
			(stroke
				(width 0.1)
				(type default)
			)
			(layer "F.Fab")
		)
		(fp_line
			(start 0.67945 -0.3048)
			(end 0.67945 0.3048)
			(stroke
				(width 0.1)
				(type default)
			)
			(layer "F.Fab")
		)
		(fp_line
			(start 0.67945 0.3048)
			(end 0.120396 0.3048)
			(stroke
				(width 0.1)
				(type default)
			)
			(layer "F.Fab")
		)
		(pad "1" smd circle
			(at -0.40005 0)
			(size 0 0)
			(layers "F.Cu" "F.Mask" "F.Paste")
			(net "P12V_AUX")
		)
		(pad "2" smd circle
			(at 0.40005 0)
			(size 0 0)
			(layers "F.Cu" "F.Mask" "F.Paste")
			(net "GND")
		)
	)
	(footprint ""
		(layer "F.Cu")
		(at 335.82991 -150.686262 90)
		(property "Reference" "PL78"
			(at -5.08 -5.81533 90)
			(unlocked yes)
			(layer "F.SilkS")
			(effects
				(font
					(size 0.7874 0.5842)
					(thickness 0.1524)
				)
				(justify left)
			)
		)
		(property "Value" ""
			(at 0 0 90)
			(layer "F.Fab")
			(effects
				(font
					(size 1.27 1.27)
				)
			)
		)
		(duplicate_pad_numbers_are_jumpers no)
		(fp_line
			(start 5.1054 -5.100066)
			(end -5.1054 -5.100066)
			(stroke
				(width 0.1524)
				(type default)
			)
			(layer "F.SilkS")
		)
		(fp_line
			(start -5.1054 -5.100066)
			(end -5.1054 -1.8796)
			(stroke
				(width 0.1524)
				(type default)
			)
			(layer "F.SilkS")
		)
		(fp_line
			(start 5.1054 -1.8796)
			(end 5.1054 -5.100066)
			(stroke
				(width 0.1524)
				(type default)
			)
			(layer "F.SilkS")
		)
		(fp_line
			(start -5.1054 1.8796)
			(end -5.1054 5.100066)
			(stroke
				(width 0.1524)
				(type default)
			)
			(layer "F.SilkS")
		)
		(fp_line
			(start 5.1054 5.100066)
			(end 5.1054 1.8796)
			(stroke
				(width 0.1524)
				(type default)
			)
			(layer "F.SilkS")
		)
		(fp_line
			(start -5.1054 5.100066)
			(end 5.1054 5.100066)
			(stroke
				(width 0.1524)
				(type default)
			)
			(layer "F.SilkS")
		)
		(fp_line
			(start 5.1054 -5.100066)
			(end 5.1054 5.100066)
			(stroke
				(width 0.1)
				(type default)
			)
			(layer "F.Fab")
		)
		(fp_line
			(start -5.1054 -5.100066)
			(end 5.1054 -5.100066)
			(stroke
				(width 0.1)
				(type default)
			)
			(layer "F.Fab")
		)
		(fp_line
			(start 5.1054 5.100066)
			(end -5.1054 5.100066)
			(stroke
				(width 0.1)
				(type default)
			)
			(layer "F.Fab")
		)
		(fp_line
			(start -5.1054 5.100066)
			(end -5.1054 -5.100066)
			(stroke
				(width 0.1)
				(type default)
			)
			(layer "F.Fab")
		)
		(pad "1" smd rect
			(at -3.999992 0 90)
			(size 3.5052 3.5052)
			(layers "F.Cu" "F.Mask" "F.Paste")
			(net "SW_PVDD18_S5_P0_SW")
		)
		(pad "2" smd rect
			(at 3.999992 0 90)
			(size 3.5052 3.5052)
			(layers "F.Cu" "F.Mask" "F.Paste")
			(net "PVDD18_S5_P0")
		)
	)
	(footprint ""
		(layer "F.Cu")
		(at 391.291318 -76.407264)
		(property "Reference" "R1309"
			(at 0 0 0)
			(layer "F.SilkS")
			(hide yes)
			(effects
				(font
					(size 1.27 1.27)
				)
			)
		)
		(property "Value" ""
			(at 0 0 0)
			(layer "F.Fab")
			(effects
				(font
					(size 1.27 1.27)
				)
			)
		)
		(duplicate_pad_numbers_are_jumpers no)
		(fp_line
			(start -0.7874 -0.4064)
			(end 0.7874 -0.4064)
			(stroke
				(width 0.1524)
				(type default)
			)
			(layer "F.SilkS")
		)
		(fp_line
			(start -0.7874 0.4064)
			(end -0.7874 -0.4064)
			(stroke
				(width 0.1524)
				(type default)
			)
			(layer "F.SilkS")
		)
		(fp_line
			(start 0.7874 -0.4064)
			(end 0.7874 0.4064)
			(stroke
				(width 0.1524)
				(type default)
			)
			(layer "F.SilkS")
		)
		(fp_line
			(start 0.7874 0.4064)
			(end -0.7874 0.4064)
			(stroke
				(width 0.1524)
				(type default)
			)
			(layer "F.SilkS")
		)
		(fp_line
			(start -0.67945 -0.305054)
			(end -0.12065 -0.305054)
			(stroke
				(width 0.1)
				(type default)
			)
			(layer "F.Fab")
		)
		(fp_line
			(start -0.67945 0.3048)
			(end -0.67945 -0.305054)
			(stroke
				(width 0.1)
				(type default)
			)
			(layer "F.Fab")
		)
		(fp_line
			(start -0.12065 -0.305054)
			(end -0.12065 -0.2794)
			(stroke
				(width 0.1)
				(type default)
			)
			(layer "F.Fab")
		)
		(fp_line
			(start -0.12065 -0.2794)
			(end 0.12065 -0.2794)
			(stroke
				(width 0.1)
				(type default)
			)
			(layer "F.Fab")
		)
		(fp_line
			(start -0.12065 0.2794)
			(end -0.12065 0.3048)
			(stroke
				(width 0.1)
				(type default)
			)
			(layer "F.Fab")
		)
		(fp_line
			(start -0.12065 0.3048)
			(end -0.67945 0.3048)
			(stroke
				(width 0.1)
				(type default)
			)
			(layer "F.Fab")
		)
		(fp_line
			(start 0.120396 0.2794)
			(end -0.12065 0.2794)
			(stroke
				(width 0.1)
				(type default)
			)
			(layer "F.Fab")
		)
		(fp_line
			(start 0.120396 0.3048)
			(end 0.120396 0.2794)
			(stroke
				(width 0.1)
				(type default)
			)
			(layer "F.Fab")
		)
		(fp_line
			(start 0.12065 -0.3048)
			(end 0.67945 -0.3048)
			(stroke
				(width 0.1)
				(type default)
			)
			(layer "F.Fab")
		)
		(fp_line
			(start 0.12065 -0.2794)
			(end 0.12065 -0.3048)
			(stroke
				(width 0.1)
				(type default)
			)
			(layer "F.Fab")
		)
		(fp_line
			(start 0.67945 -0.3048)
			(end 0.67945 0.3048)
			(stroke
				(width 0.1)
				(type default)
			)
			(layer "F.Fab")
		)
		(fp_line
			(start 0.67945 0.3048)
			(end 0.120396 0.3048)
			(stroke
				(width 0.1)
				(type default)
			)
			(layer "F.Fab")
		)
		(pad "1" smd circle
			(at -0.40005 0)
			(size 0 0)
			(layers "F.Cu" "F.Mask" "F.Paste")
			(net "GND")
		)
		(pad "2" smd circle
			(at 0.40005 0)
			(size 0 0)
			(layers "F.Cu" "F.Mask" "F.Paste")
			(net "INA230_6_A0")
		)
	)
	(footprint ""
		(layer "F.Cu")
		(at 90.380312 -74.52106 -90)
		(property "Reference" "PR3856"
			(at 0 0 270)
			(layer "F.SilkS")
			(hide yes)
			(effects
				(font
					(size 1.27 1.27)
				)
			)
		)
		(property "Value" ""
			(at 0 0 270)
			(layer "F.Fab")
			(effects
				(font
					(size 1.27 1.27)
				)
			)
		)
		(duplicate_pad_numbers_are_jumpers no)
		(fp_line
			(start -0.7874 0.4064)
			(end -0.7874 -0.4064)
			(stroke
				(width 0.1524)
				(type default)
			)
			(layer "F.SilkS")
		)
		(fp_line
			(start 0.7874 0.4064)
			(end -0.7874 0.4064)
			(stroke
				(width 0.1524)
				(type default)
			)
			(layer "F.SilkS")
		)
		(fp_line
			(start -0.7874 -0.4064)
			(end 0.7874 -0.4064)
			(stroke
				(width 0.1524)
				(type default)
			)
			(layer "F.SilkS")
		)
		(fp_line
			(start 0.7874 -0.4064)
			(end 0.7874 0.4064)
			(stroke
				(width 0.1524)
				(type default)
			)
			(layer "F.SilkS")
		)
		(fp_line
			(start -0.67945 0.3048)
			(end -0.67945 -0.305054)
			(stroke
				(width 0.1)
				(type default)
			)
			(layer "F.Fab")
		)
		(fp_line
			(start -0.12065 0.3048)
			(end -0.67945 0.3048)
			(stroke
				(width 0.1)
				(type default)
			)
			(layer "F.Fab")
		)
		(fp_line
			(start 0.120396 0.3048)
			(end 0.120396 0.2794)
			(stroke
				(width 0.1)
				(type default)
			)
			(layer "F.Fab")
		)
		(fp_line
			(start 0.67945 0.3048)
			(end 0.120396 0.3048)
			(stroke
				(width 0.1)
				(type default)
			)
			(layer "F.Fab")
		)
		(fp_line
			(start -0.12065 0.2794)
			(end -0.12065 0.3048)
			(stroke
				(width 0.1)
				(type default)
			)
			(layer "F.Fab")
		)
		(fp_line
			(start 0.120396 0.2794)
			(end -0.12065 0.2794)
			(stroke
				(width 0.1)
				(type default)
			)
			(layer "F.Fab")
		)
		(fp_line
			(start -0.12065 -0.2794)
			(end 0.12065 -0.2794)
			(stroke
				(width 0.1)
				(type default)
			)
			(layer "F.Fab")
		)
		(fp_line
			(start 0.12065 -0.2794)
			(end 0.12065 -0.3048)
			(stroke
				(width 0.1)
				(type default)
			)
			(layer "F.Fab")
		)
		(fp_line
			(start 0.12065 -0.3048)
			(end 0.67945 -0.3048)
			(stroke
				(width 0.1)
				(type default)
			)
			(layer "F.Fab")
		)
		(fp_line
			(start 0.67945 -0.3048)
			(end 0.67945 0.3048)
			(stroke
				(width 0.1)
				(type default)
			)
			(layer "F.Fab")
		)
		(fp_line
			(start -0.67945 -0.305054)
			(end -0.12065 -0.305054)
			(stroke
				(width 0.1)
				(type default)
			)
			(layer "F.Fab")
		)
		(fp_line
			(start -0.12065 -0.305054)
			(end -0.12065 -0.2794)
			(stroke
				(width 0.1)
				(type default)
			)
			(layer "F.Fab")
		)
		(pad "1" smd circle
			(at -0.40005 0 270)
			(size 0 0)
			(layers "F.Cu" "F.Mask" "F.Paste")
			(net "GND")
		)
		(pad "2" smd circle
			(at 0.40005 0 270)
			(size 0 0)
			(layers "F.Cu" "F.Mask" "F.Paste")
			(net "P3V3_OCP_ILIMIT_2")
		)
	)
	(footprint ""
		(layer "F.Cu")
		(at 346.833444 -378.95403 -90)
		(property "Reference" "C947"
			(at 0 0 270)
			(layer "F.SilkS")
			(hide yes)
			(effects
				(font
					(size 1.27 1.27)
				)
			)
		)
		(property "Value" ""
			(at 0 0 270)
			(layer "F.Fab")
			(effects
				(font
					(size 1.27 1.27)
				)
			)
		)
		(duplicate_pad_numbers_are_jumpers no)
		(fp_line
			(start -0.299974 0.150114)
			(end -0.299974 -0.150114)
			(stroke
				(width 0.1)
				(type default)
			)
			(layer "F.Fab")
		)
		(fp_line
			(start 0.299974 0.150114)
			(end -0.299974 0.150114)
			(stroke
				(width 0.1)
				(type default)
			)
			(layer "F.Fab")
		)
		(fp_line
			(start -0.299974 -0.150114)
			(end 0.299974 -0.150114)
			(stroke
				(width 0.1)
				(type default)
			)
			(layer "F.Fab")
		)
		(fp_line
			(start 0.299974 -0.150114)
			(end 0.299974 0.150114)
			(stroke
				(width 0.1)
				(type default)
			)
			(layer "F.Fab")
		)
		(pad "1" smd rect
			(at -0.2667 0 270)
			(size 0.3048 0.381)
			(layers "F.Cu" "F.Mask" "F.Paste")
			(net "P5E_CPU0_P1_TX_C_DP<9>")
		)
		(pad "2" smd rect
			(at 0.2667 0 270)
			(size 0.3048 0.381)
			(layers "F.Cu" "F.Mask" "F.Paste")
			(net "P5E_CPU0_P1_TX_DP<9>")
		)
	)
	(footprint ""
		(layer "F.Cu")
		(at 298.989496 -381.41783 -90)
		(property "Reference" "C929"
			(at 0 0 270)
			(layer "F.SilkS")
			(hide yes)
			(effects
				(font
					(size 1.27 1.27)
				)
			)
		)
		(property "Value" ""
			(at 0 0 270)
			(layer "F.Fab")
			(effects
				(font
					(size 1.27 1.27)
				)
			)
		)
		(duplicate_pad_numbers_are_jumpers no)
		(fp_line
			(start -0.299974 0.150114)
			(end -0.299974 -0.150114)
			(stroke
				(width 0.1)
				(type default)
			)
			(layer "F.Fab")
		)
		(fp_line
			(start 0.299974 0.150114)
			(end -0.299974 0.150114)
			(stroke
				(width 0.1)
				(type default)
			)
			(layer "F.Fab")
		)
		(fp_line
			(start -0.299974 -0.150114)
			(end 0.299974 -0.150114)
			(stroke
				(width 0.1)
				(type default)
			)
			(layer "F.Fab")
		)
		(fp_line
			(start 0.299974 -0.150114)
			(end 0.299974 0.150114)
			(stroke
				(width 0.1)
				(type default)
			)
			(layer "F.Fab")
		)
		(pad "1" smd rect
			(at -0.2667 0 270)
			(size 0.3048 0.381)
			(layers "F.Cu" "F.Mask" "F.Paste")
			(net "P5E_CPU0_P0_TX_C_DP<2>")
		)
		(pad "2" smd rect
			(at 0.2667 0 270)
			(size 0.3048 0.381)
			(layers "F.Cu" "F.Mask" "F.Paste")
			(net "P5E_CPU0_P0_TX_DP<2>")
		)
	)
	(footprint ""
		(layer "F.Cu")
		(at 103.185722 -29.819854 90)
		(property "Reference" "R344"
			(at 0 0 90)
			(layer "F.SilkS")
			(hide yes)
			(effects
				(font
					(size 1.27 1.27)
				)
			)
		)
		(property "Value" ""
			(at 0 0 90)
			(layer "F.Fab")
			(effects
				(font
					(size 1.27 1.27)
				)
			)
		)
		(duplicate_pad_numbers_are_jumpers no)
		(fp_line
			(start 0.32512 -0.175006)
			(end 0.32512 0.175006)
			(stroke
				(width 0.1)
				(type default)
			)
			(layer "F.Fab")
		)
		(fp_line
			(start -0.32512 -0.175006)
			(end 0.32512 -0.175006)
			(stroke
				(width 0.1)
				(type default)
			)
			(layer "F.Fab")
		)
		(fp_line
			(start 0.32512 0.175006)
			(end -0.32512 0.175006)
			(stroke
				(width 0.1)
				(type default)
			)
			(layer "F.Fab")
		)
		(fp_line
			(start -0.32512 0.175006)
			(end -0.32512 -0.175006)
			(stroke
				(width 0.1)
				(type default)
			)
			(layer "F.Fab")
		)
		(pad "1" smd rect
			(at -0.2667 0 90)
			(size 0.3048 0.381)
			(layers "F.Cu" "F.Mask" "F.Paste")
			(net "USB3_CPU0_BMC_TX_C2_DP")
		)
		(pad "2" smd rect
			(at 0.2667 0 270)
			(size 0.3048 0.381)
			(layers "F.Cu" "F.Mask" "F.Paste")
			(net "GND")
		)
	)
)
